(kicad_pcb
	(version 20221018)
	(generator pcbnew)
	(general
    (thickness 1.518)
  )
	(paper "A4")
	(title_block
    (title "Kria K26 Devboard")
    (date "2024-03-26")
    (rev "1.2.5")
    (comment 1 "www.antmicro.com")
    (comment 2 "Antmicro Ltd.")
		(comment 9 "footprints 405-415 of 660")
	)
	(layers
    (0 "F.Cu" mixed)
    (1 "In1.Cu" power)
    (2 "In2.Cu" mixed)
    (3 "In3.Cu" power)
    (4 "In4.Cu" mixed)
    (5 "In5.Cu" power)
    (6 "In6.Cu" mixed)
    (31 "B.Cu" power)
    (32 "B.Adhes" user "B.Adhesive")
    (33 "F.Adhes" user "F.Adhesive")
    (34 "B.Paste" user)
    (35 "F.Paste" user)
    (36 "B.SilkS" user "B.Silkscreen")
    (37 "F.SilkS" user "F.Silkscreen")
    (38 "B.Mask" user)
    (39 "F.Mask" user)
    (40 "Dwgs.User" user "User.Drawings")
    (41 "Cmts.User" user "User.Comments")
    (42 "Eco1.User" user "User.Eco1")
    (43 "Eco2.User" user "User.Eco2")
    (44 "Edge.Cuts" user)
    (45 "Margin" user)
    (46 "B.CrtYd" user "B.Courtyard")
    (47 "F.CrtYd" user "F.Courtyard")
    (48 "B.Fab" user)
    (49 "F.Fab" user)
  )
	(footprint "kria-k26-devboard-footprints:R_0603_1608Metric" (layer "F.Cu")
    (at 166.1 115.4 180)
    (descr "Resistor SMD 0603")
    (tags "resistor SMD 0603")
    (property "Author" "Antmicro")
    (property "License" "Apache-2.0")
    (property "MPN" "PMR03EZPJ000")
    (property "Manufacturer" "ROHM Semiconductor")
    (property "Max. Curr." "22.4A")
    (property "Sheetfile" "dc-dc-conventers.kicad_sch")
    (property "Sheetname" "DC/DC conventers")
    (property "Val" "0R")
    (property "ki_description" "Metal strip 0Ohm jumper 22.4A")
    (property "ki_keywords" "Metal strip 0Ohm jumper 22.4A high power hpwr current")
    (attr smd)
    (fp_text reference "R156" (at 1.46 -0.88 270) (layer "F.SilkS")
        (effects (font (size 0.7 0.7) (thickness 0.15)) (justify left bottom))
    )
    (fp_text value "R_0R_22.4A_0603" (at 0 1.6 180) (layer "F.Fab") hide
        (effects (font (size 0.7 0.7) (thickness 0.15)) (justify left bottom))
    )
    (fp_text user "${REFERENCE}" (at -1.25 3.898 180) (layer "F.Fab") hide
        (effects (font (size 0.7 0.7) (thickness 0.15)) (justify left bottom))
    )
    (fp_text user "License: Apache-2.0" (at -1.25 5.9 180) (layer "F.Fab") hide
        (effects (font (size 0.7 0.7) (thickness 0.15)) (justify left bottom))
    )
    (fp_text user "Author: Antmicro" (at -1.25 4.9 180) (layer "F.Fab") hide
        (effects (font (size 0.7 0.7) (thickness 0.15)) (justify left bottom))
    )
    (fp_line (start -0.3 -0.3) (end 0.3 -0.3)
      (stroke (width 0.15) (type solid)) (layer "F.SilkS"))
    (fp_line (start -0.3 0.3) (end 0.3 0.3)
      (stroke (width 0.15) (type solid)) (layer "F.SilkS"))
    (fp_rect (start -1.25 -0.7) (end 1.25 0.7)
      (stroke (width 0.05) (type solid)) (fill none) (layer "F.CrtYd"))
    (fp_rect (start -0.8 -0.4) (end 0.8 0.4)
      (stroke (width 0.15) (type solid)) (fill none) (layer "F.Fab"))
    (pad "1" smd roundrect (at -0.7 0 180) (size 0.6 0.8) (layers "F.Cu" "F.Paste" "F.Mask") (roundrect_rratio 0.2)
      (net 768 "/Power Supply/DC/DC conventers/PS_1V2_OUT") (pintype "passive"))
    (pad "2" smd roundrect (at 0.7 0 180) (size 0.6 0.8) (layers "F.Cu" "F.Paste" "F.Mask") (roundrect_rratio 0.2)
      (net 18 "PS_1V2") (pintype "passive"))
  )
	(footprint "kria-k26-devboard-footprints:TP_SMD_0.75mm" (layer "F.Cu")
    (at 102.65 148.8)
    (property "Author" "Antmicro")
    (property "License" "Apache-2.0")
    (property "MPN" "")
    (property "Manufacturer" "")
    (property "Sheetfile" "i2c.kicad_sch")
    (property "Sheetname" "I2C ")
    (property "ki_description" "Test Point 0.75mm")
    (attr exclude_from_pos_files)
    (fp_text reference "TP61" (at -2.93 0.33 180) (layer "F.SilkS")
        (effects (font (size 0.7 0.7) (thickness 0.15)) (justify left bottom))
    )
    (fp_text value "TP_0.75mm_SMD" (at 0 1.2) (layer "F.Fab") hide
        (effects (font (size 0.7 0.7) (thickness 0.15)) (justify left bottom))
    )
    (fp_text user "License: Apache-2.0" (at -0.4 5.101) (layer "F.Fab") hide
        (effects (font (size 0.7 0.7) (thickness 0.15)) (justify left bottom))
    )
    (fp_text user "${REFERENCE}" (at -0.4 2.7) (layer "F.Fab") hide
        (effects (font (size 0.7 0.7) (thickness 0.15)) (justify left bottom))
    )
    (fp_text user "Author: Antmicro" (at -0.4 3.901) (layer "F.Fab") hide
        (effects (font (size 0.7 0.7) (thickness 0.15)) (justify left bottom))
    )
    (pad "1" smd circle (at 0 0) (size 0.75 0.75) (layers "F.Cu" "F.Mask")
      (net 153 "/I2C /MIO24_I2C_SCK") (pinfunction "1") (pintype "passive"))
  )
	(footprint "kria-k26-devboard-footprints:TP_SMD_0.75mm" (layer "F.Cu")
    (at 154.7492 150.8 -90)
    (property "Author" "Antmicro")
    (property "License" "Apache-2.0")
    (property "MPN" "")
    (property "Manufacturer" "")
    (property "Sheetfile" "debug.kicad_sch")
    (property "Sheetname" "Debug and JTAG")
    (property "ki_description" "Test Point 0.75mm")
    (attr exclude_from_pos_files)
    (fp_text reference "TP64" (at -0.47 -0.4308 -90) (layer "F.SilkS")
        (effects (font (size 0.7 0.7) (thickness 0.15)) (justify left bottom))
    )
    (fp_text value "TP_0.75mm_SMD" (at 0 1.2 -90) (layer "F.Fab") hide
        (effects (font (size 0.7 0.7) (thickness 0.15)) (justify left bottom))
    )
    (fp_text user "License: Apache-2.0" (at -0.4 5.101 -90) (layer "F.Fab") hide
        (effects (font (size 0.7 0.7) (thickness 0.15)) (justify left bottom))
    )
    (fp_text user "${REFERENCE}" (at -0.4 2.7 -90) (layer "F.Fab") hide
        (effects (font (size 0.7 0.7) (thickness 0.15)) (justify left bottom))
    )
    (fp_text user "Author: Antmicro" (at -0.4 3.901 -90) (layer "F.Fab") hide
        (effects (font (size 0.7 0.7) (thickness 0.15)) (justify left bottom))
    )
    (pad "1" smd circle (at 0 0 270) (size 0.75 0.75) (layers "F.Cu" "F.Mask")
      (net 700 "Net-(U40-CDBUS1)") (pinfunction "1") (pintype "passive"))
  )
	(footprint "kria-k26-devboard-footprints:Fiducial_1mm_Mask2mm" (layer "F.Cu")
    (at 174.4 55.1)
    (descr "Circular Fiducial, 1mm bare copper, 3mm soldermask opening")
    (tags "fiducial")
    (attr smd board_only exclude_from_bom)
    (fp_text reference "FID3" (at -0.07 3.21 90) (layer "F.SilkS")
        (effects (font (size 1 1) (thickness 0.15)))
    )
    (fp_text value "Fiducial_1mm_Mask2mm" (at 0 2.6035) (layer "F.Fab") hide
        (effects (font (size 1 1) (thickness 0.15)))
    )
    (fp_text user "License: Apache-2.0" (at -1.25 7.003) (layer "F.Fab") hide
        (effects (font (size 0.7 0.7) (thickness 0.15)) (justify left bottom))
    )
    (fp_text user "${REFERENCE}" (at 0 0) (layer "F.Fab")
        (effects (font (size 0.4 0.4) (thickness 0.06)))
    )
    (fp_text user "Author: Antmicro" (at -1.25 5.803) (layer "F.Fab") hide
        (effects (font (size 0.7 0.7) (thickness 0.15)) (justify left bottom))
    )
    (fp_circle (center 0 0) (end 1.24 0)
      (stroke (width 0.05) (type solid)) (fill none) (layer "F.CrtYd"))
    (fp_circle (center 0 0) (end 0.999 0)
      (stroke (width 0.15) (type solid)) (fill none) (layer "F.Fab"))
    (pad "" smd circle (at 0 0) (size 1 1) (layers "F.Cu" "F.Mask")
      (solder_mask_margin 0.5) (clearance 0.5))
  )
	(footprint "kria-k26-devboard-footprints:XILINX-KRIA-K26" locked (layer "F.Cu")
    (at 86.38 147.61)
    (property "Author" "Antmicro")
    (property "Description" "System-On-Modules - SOM K26C SOM")
    (property "License" "Apache-2.0")
    (property "MPN" "SM-K26-XCL2GC")
    (property "Manufacturer" "Xilinx")
    (property "Sheetfile" "k26_som.kicad_sch")
    (property "Sheetname" "Xilinx K26 SOM")
    (attr exclude_from_pos_files)
    (fp_text reference "M1" (at 0 0.5) (layer "F.SilkS") hide
        (effects (font (size 1 1) (thickness 0.15)))
    )
    (fp_text value "XILINX-KRIA-K26" (at 4.572 1.976) (layer "F.Fab") hide
        (effects (font (size 1 1) (thickness 0.15)))
    )
    (fp_text user "Author: Antmicro" (at -0.002 5.176) (layer "F.Fab") hide
        (effects (font (size 0.7 0.7) (thickness 0.15)) (justify left bottom))
    )
    (fp_text user "${REFERENCE}" (at -0.002 3.975) (layer "F.Fab") hide
        (effects (font (size 0.7 0.7) (thickness 0.15)) (justify left bottom))
    )
    (fp_text user "License: Apache-2.0" (at -0.002 6.376) (layer "F.Fab") hide
        (effects (font (size 0.7 0.7) (thickness 0.15)) (justify left bottom))
    )
    (fp_line (start 0 -56.82) (end 0 -3.181)
      (stroke (width 0.15) (type solid)) (layer "F.SilkS"))
    (fp_line (start 3.18 -60) (end 73.819 -60)
      (stroke (width 0.15) (type solid)) (layer "F.SilkS"))
    (fp_line (start 3.18 0) (end 73.819 0)
      (stroke (width 0.15) (type solid)) (layer "F.SilkS"))
    (fp_line (start 76.999 -56.82) (end 76.999 -3.181)
      (stroke (width 0.15) (type solid)) (layer "F.SilkS"))
    (fp_arc (start 0 -56.82) (mid 0.931 -59.069) (end 3.18 -60)
      (stroke (width 0.15) (type solid)) (layer "F.SilkS"))
    (fp_arc (start 3.18 0) (mid 0.931146 -0.931854) (end 0 -3.181)
      (stroke (width 0.15) (type solid)) (layer "F.SilkS"))
    (fp_arc (start 73.819 -60) (mid 76.06801 -59.06901) (end 76.999 -56.82)
      (stroke (width 0.15) (type solid)) (layer "F.SilkS"))
    (fp_arc (start 76.999 -3.181) (mid 76.067854 -0.931854) (end 73.819 0)
      (stroke (width 0.15) (type solid)) (layer "F.SilkS"))
    (fp_line (start 2.45 -51.66) (end 7.11 -51.66)
      (stroke (width 0.05) (type solid)) (layer "F.CrtYd"))
    (fp_line (start 2.45 -8.34) (end 2.45 -51.66)
      (stroke (width 0.05) (type solid)) (layer "F.CrtYd"))
    (fp_line (start 7.11 -51.66) (end 7.95 -50.83)
      (stroke (width 0.05) (type solid)) (layer "F.CrtYd"))
    (fp_line (start 7.11 -8.34) (end 2.45 -8.34)
      (stroke (width 0.05) (type solid)) (layer "F.CrtYd"))
    (fp_line (start 7.95 -50.83) (end 7.95 -9.18)
      (stroke (width 0.05) (type solid)) (layer "F.CrtYd"))
    (fp_line (start 7.95 -9.18) (end 7.11 -8.34)
      (stroke (width 0.05) (type solid)) (layer "F.CrtYd"))
    (fp_line (start 69.04 -51.66) (end 73.71 -51.66)
      (stroke (width 0.05) (type solid)) (layer "F.CrtYd"))
    (fp_line (start 69.04 -8.34) (end 69.04 -51.66)
      (stroke (width 0.05) (type solid)) (layer "F.CrtYd"))
    (fp_line (start 73.71 -51.66) (end 74.54 -50.83)
      (stroke (width 0.05) (type solid)) (layer "F.CrtYd"))
    (fp_line (start 73.71 -8.34) (end 69.04 -8.34)
      (stroke (width 0.05) (type solid)) (layer "F.CrtYd"))
    (fp_line (start 74.54 -50.83) (end 74.54 -9.18)
      (stroke (width 0.05) (type solid)) (layer "F.CrtYd"))
    (fp_line (start 74.54 -9.18) (end 73.71 -8.34)
      (stroke (width 0.05) (type solid)) (layer "F.CrtYd"))
  )
	(footprint "kria-k26-devboard-footprints:SOT-416" (layer "F.Cu")
    (at 183.2 117.5 90)
    (descr "SOT-416")
    (tags "SOT-416")
    (property "Author" "Antmicro")
    (property "License" "Apache-2.0")
    (property "MPN" "DTC014TEBTL")
    (property "Manufacturer" "ROHM Semiconductor")
    (property "Sheetfile" "dc-dc-conventers.kicad_sch")
    (property "Sheetname" "DC/DC conventers")
    (property "ki_description" "Digital NPN Transistor, 10k/NONE, EMT-3")
    (attr smd)
    (fp_text reference "Q18" (at -1.8 -0.89 180) (layer "F.SilkS")
        (effects (font (size 0.7 0.7) (thickness 0.15)) (justify left bottom))
    )
    (fp_text value "DTC014T_SOT-416" (at 0 2 90) (layer "F.Fab") hide
        (effects (font (size 0.7 0.7) (thickness 0.15)) (justify left bottom))
    )
    (fp_text user "Author: Antmicro" (at -1 4.602 90) (layer "F.Fab") hide
        (effects (font (size 0.7 0.7) (thickness 0.15)) (justify left bottom))
    )
    (fp_text user "${REFERENCE}" (at -1 3.4 90) (layer "F.Fab") hide
        (effects (font (size 0.7 0.7) (thickness 0.15)) (justify left bottom))
    )
    (fp_text user "License: Apache-2.0" (at -1 5.802 90) (layer "F.Fab") hide
        (effects (font (size 0.7 0.7) (thickness 0.15)) (justify left bottom))
    )
    (fp_line (start -0.5 -0.15) (end -0.5 0.15)
      (stroke (width 0.15) (type solid)) (layer "F.SilkS"))
    (fp_line (start 0.5 0.9) (end -0.5 0.9)
      (stroke (width 0.15) (type solid)) (layer "F.SilkS"))
    (fp_line (start 0.5 0.9) (end 0.5 0.7)
      (stroke (width 0.15) (type solid)) (layer "F.SilkS"))
    (fp_line (start 0.508 -0.9) (end -0.5 -0.9)
      (stroke (width 0.15) (type solid)) (layer "F.SilkS"))
    (fp_line (start 0.508 -0.9) (end 0.508 -0.592)
      (stroke (width 0.15) (type solid)) (layer "F.SilkS"))
    (fp_rect (start -1 -1.05) (end 1 1.05)
      (stroke (width 0.05) (type solid)) (fill none) (layer "F.CrtYd"))
    (fp_line (start -0.05 -0.9) (end -0.45 -0.5)
      (stroke (width 0.15) (type solid)) (layer "F.Fab"))
    (fp_rect (start 0.45 0.9) (end -0.45 -0.9)
      (stroke (width 0.15) (type solid)) (fill none) (layer "F.Fab"))
    (pad "1" smd rect (at -0.652 -0.5 90) (size 0.6 0.5) (layers "F.Cu" "F.Paste" "F.Mask")
      (net 767 "/Power Supply/DC/DC conventers/PS_1V8_OUT") (pinfunction "B") (pintype "input"))
    (pad "2" smd rect (at -0.652 0.498 90) (size 0.6 0.5) (layers "F.Cu" "F.Paste" "F.Mask")
      (net 1 "GND") (pinfunction "E") (pintype "passive"))
    (pad "3" smd rect (at 0.65 0 90) (size 0.6 0.5) (layers "F.Cu" "F.Paste" "F.Mask")
      (net 337 "Net-(Q18-C)") (pinfunction "C") (pintype "passive"))
  )
	(footprint "kria-k26-devboard-footprints:TP_SMD_0.75mm" (layer "F.Cu")
    (at 82.229289 107.9 180)
    (property "Author" "Antmicro")
    (property "License" "Apache-2.0")
    (property "MPN" "")
    (property "Manufacturer" "")
    (property "Sheetfile" "k26_som.kicad_sch")
    (property "Sheetname" "Xilinx K26 SOM")
    (property "ki_description" "Test Point 0.75mm")
    (attr exclude_from_pos_files)
    (fp_text reference "TP56" (at 4.029289 -0.27 180) (layer "F.SilkS")
        (effects (font (size 0.7 0.7) (thickness 0.15)) (justify left bottom))
    )
    (fp_text value "TP_0.75mm_SMD" (at 0 1.2 180) (layer "F.Fab") hide
        (effects (font (size 0.7 0.7) (thickness 0.15)) (justify left bottom))
    )
    (fp_text user "${REFERENCE}" (at -0.4 2.7 180) (layer "F.Fab") hide
        (effects (font (size 0.7 0.7) (thickness 0.15)) (justify left bottom))
    )
    (fp_text user "License: Apache-2.0" (at -0.4 5.101 180) (layer "F.Fab") hide
        (effects (font (size 0.7 0.7) (thickness 0.15)) (justify left bottom))
    )
    (fp_text user "Author: Antmicro" (at -0.4 3.901 180) (layer "F.Fab") hide
        (effects (font (size 0.7 0.7) (thickness 0.15)) (justify left bottom))
    )
    (pad "1" smd circle (at 0 0 180) (size 0.75 0.75) (layers "F.Cu" "F.Mask")
      (net 474 "/Xilinx K26 SOM/PWRGD_LPD_M2C") (pinfunction "1") (pintype "passive"))
  )
	(footprint "kria-k26-devboard-footprints:TP_SMD_0.75mm" (layer "F.Cu")
    (at 81.55 104.95 180)
    (property "Author" "Antmicro")
    (property "License" "Apache-2.0")
    (property "MPN" "")
    (property "Manufacturer" "")
    (property "Sheetfile" "k26_som.kicad_sch")
    (property "Sheetname" "Xilinx K26 SOM")
    (property "ki_description" "Test Point 0.75mm")
    (attr exclude_from_pos_files)
    (fp_text reference "TP54" (at 3.36 -0.2808 180) (layer "F.SilkS")
        (effects (font (size 0.7 0.7) (thickness 0.15)) (justify left bottom))
    )
    (fp_text value "TP_0.75mm_SMD" (at 0 1.2 180) (layer "F.Fab") hide
        (effects (font (size 0.7 0.7) (thickness 0.15)) (justify left bottom))
    )
    (fp_text user "${REFERENCE}" (at -0.4 2.7 180) (layer "F.Fab") hide
        (effects (font (size 0.7 0.7) (thickness 0.15)) (justify left bottom))
    )
    (fp_text user "License: Apache-2.0" (at -0.4 5.101 180) (layer "F.Fab") hide
        (effects (font (size 0.7 0.7) (thickness 0.15)) (justify left bottom))
    )
    (fp_text user "Author: Antmicro" (at -0.4 3.901 180) (layer "F.Fab") hide
        (effects (font (size 0.7 0.7) (thickness 0.15)) (justify left bottom))
    )
    (pad "1" smd circle (at 0 0 180) (size 0.75 0.75) (layers "F.Cu" "F.Mask")
      (net 457 "/Xilinx K26 SOM/PWROFF_C2M_L") (pinfunction "1") (pintype "passive"))
  )
	(footprint "kria-k26-devboard-footprints:TP_SMD_0.75mm" (layer "F.Cu")
    (at 82.229289 105.95 180)
    (property "Author" "Antmicro")
    (property "License" "Apache-2.0")
    (property "MPN" "")
    (property "Manufacturer" "")
    (property "Sheetfile" "k26_som.kicad_sch")
    (property "Sheetname" "Xilinx K26 SOM")
    (property "ki_description" "Test Point 0.75mm")
    (attr exclude_from_pos_files)
    (fp_text reference "TP53" (at 4.029289 -0.27 180) (layer "F.SilkS")
        (effects (font (size 0.7 0.7) (thickness 0.15)) (justify left bottom))
    )
    (fp_text value "TP_0.75mm_SMD" (at 0 1.2 180) (layer "F.Fab") hide
        (effects (font (size 0.7 0.7) (thickness 0.15)) (justify left bottom))
    )
    (fp_text user "License: Apache-2.0" (at -0.4 5.101 180) (layer "F.Fab") hide
        (effects (font (size 0.7 0.7) (thickness 0.15)) (justify left bottom))
    )
    (fp_text user "Author: Antmicro" (at -0.4 3.901 180) (layer "F.Fab") hide
        (effects (font (size 0.7 0.7) (thickness 0.15)) (justify left bottom))
    )
    (fp_text user "${REFERENCE}" (at -0.4 2.7 180) (layer "F.Fab") hide
        (effects (font (size 0.7 0.7) (thickness 0.15)) (justify left bottom))
    )
    (pad "1" smd circle (at 0 0 180) (size 0.75 0.75) (layers "F.Cu" "F.Mask")
      (net 456 "/Xilinx K26 SOM/PS_ERROR_STATUS_M2C") (pinfunction "1") (pintype "passive"))
  )
	(footprint "kria-k26-devboard-footprints:R_0402_1005Metric" (layer "F.Cu")
    (at 112.65 136.03 -90)
    (descr "Resistor SMD 0402")
    (tags "resistor SMD 0402")
    (property "Author" "Antmicro")
    (property "License" "Apache-2.0")
    (property "MPN" "CR0402-FX-1001GLF")
    (property "Manufacturer" "Bourns")
    (property "Sheetfile" "reset.kicad_sch")
    (property "Sheetname" "Reset logic")
    (property "Tolerance" "1%")
    (property "Val" "1k")
    (property "ki_description" "1k resistor in 0402 package with 1% tolerance")
    (attr smd)
    (fp_text reference "R85" (at 1.09 -1.26 -90) (layer "F.SilkS")
        (effects (font (size 0.7 0.7) (thickness 0.15)) (justify left bottom))
    )
    (fp_text value "R_1k_0402" (at 0 1.4 -90) (layer "F.Fab") hide
        (effects (font (size 0.7 0.7) (thickness 0.15)) (justify left bottom))
    )
    (fp_text user "${REFERENCE}" (at -0.95 3.168 -90) (layer "F.Fab") hide
        (effects (font (size 0.7 0.7) (thickness 0.15)) (justify left bottom))
    )
    (fp_text user "Author: Antmicro" (at -0.95 4.169 -90) (layer "F.Fab") hide
        (effects (font (size 0.7 0.7) (thickness 0.15)) (justify left bottom))
    )
    (fp_text user "License: Apache-2.0" (at -0.95 5.169 -90) (layer "F.Fab") hide
        (effects (font (size 0.7 0.7) (thickness 0.15)) (justify left bottom))
    )
    (fp_rect (start -0.93 -0.47) (end 0.93 0.47)
      (stroke (width 0.05) (type solid)) (fill none) (layer "F.CrtYd"))
    (fp_rect (start -0.5 -0.25) (end 0.5 0.25)
      (stroke (width 0.15) (type solid)) (fill none) (layer "F.Fab"))
    (pad "1" smd roundrect (at -0.485 0 270) (size 0.59 0.64) (layers "F.Cu" "F.Paste" "F.Mask") (roundrect_rratio 0.25)
      (net 185 "/Clock distribution/PS_CLK_EN") (pintype "passive"))
    (pad "2" smd roundrect (at 0.485 0 270) (size 0.59 0.64) (layers "F.Cu" "F.Paste" "F.Mask") (roundrect_rratio 0.25)
      (net 15 "PS_3V3") (pintype "passive"))
  )
	(footprint "kria-k26-devboard-footprints:TP_SMD_0.75mm" (layer "F.Cu")
    (at 103.7 148.8)
    (property "Author" "Antmicro")
    (property "License" "Apache-2.0")
    (property "MPN" "")
    (property "Manufacturer" "")
    (property "Sheetfile" "i2c.kicad_sch")
    (property "Sheetname" "I2C ")
    (property "ki_description" "Test Point 0.75mm")
    (attr exclude_from_pos_files)
    (fp_text reference "TP62" (at 0.24 0.33) (layer "F.SilkS")
        (effects (font (size 0.7 0.7) (thickness 0.15)) (justify left bottom))
    )
    (fp_text value "TP_0.75mm_SMD" (at 0 1.2) (layer "F.Fab") hide
        (effects (font (size 0.7 0.7) (thickness 0.15)) (justify left bottom))
    )
    (fp_text user "License: Apache-2.0" (at -0.4 5.101) (layer "F.Fab") hide
        (effects (font (size 0.7 0.7) (thickness 0.15)) (justify left bottom))
    )
    (fp_text user "${REFERENCE}" (at -0.4 2.7) (layer "F.Fab") hide
        (effects (font (size 0.7 0.7) (thickness 0.15)) (justify left bottom))
    )
    (fp_text user "Author: Antmicro" (at -0.4 3.901) (layer "F.Fab") hide
        (effects (font (size 0.7 0.7) (thickness 0.15)) (justify left bottom))
    )
    (pad "1" smd circle (at 0 0) (size 0.75 0.75) (layers "F.Cu" "F.Mask")
      (net 432 "/I2C /MIO25_I2C_SDA") (pinfunction "1") (pintype "passive"))
  )
)
